(kicad_pcb
	(version 20260206)
	(generator "pcbnew")
	(generator_version "10.0")
	(general
		(thickness 1.6)
		(legacy_teardrops no)
	)
	(paper "A4")
	(title_block
		(title "04192023_DAF0TMB3IC0_F0TG_MB_C_brd_V02_OCP.brd")
		(comment 1 "Grand Teton / footprint 230 of 8354 (J100), pads 1-113 of 291")
	)
	(layers
		(0 "F.Cu" signal "TOP")
		(4 "In1.Cu" signal "GND")
		(6 "In2.Cu" signal "IN1")
		(8 "In3.Cu" signal "GND1")
		(10 "In4.Cu" signal "IN2")
		(12 "In5.Cu" signal "GND2")
		(14 "In6.Cu" signal "IN3")
		(16 "In7.Cu" signal "GND3")
		(18 "In8.Cu" signal "VCC")
		(20 "In9.Cu" signal "VCC1")
		(22 "In10.Cu" signal "GND4")
		(24 "In11.Cu" signal "IN4")
		(26 "In12.Cu" signal "GND5")
		(28 "In13.Cu" signal "IN5")
		(30 "In14.Cu" signal "GND6")
		(32 "In15.Cu" signal "IN6")
		(34 "In16.Cu" signal "GND7")
		(2 "B.Cu" signal "BOTTOM")
		(9 "F.Adhes" user "F.Adhesive")
		(11 "B.Adhes" user "B.Adhesive")
		(13 "F.Paste" user "Package Geometry/Pastemask Top")
		(15 "B.Paste" user "Package Geometry/Pastemask Bottom")
		(5 "F.SilkS" user "Ref Des/Silkscreen Top")
		(7 "B.SilkS" user "Ref Des/Silkscreen Bottom")
		(1 "F.Mask" user "Board Geometry/Soldermask Top")
		(3 "B.Mask" user "Board Geometry/Soldermask Bottom")
		(17 "Dwgs.User" user "User.Drawings")
		(19 "Cmts.User" user "User.Comments")
		(21 "Eco1.User" user "User.Eco1")
		(23 "Eco2.User" user "User.Eco2")
		(25 "Edge.Cuts" user "Board Geometry/Outline")
		(27 "Margin" user)
		(31 "F.CrtYd" user "Package Geometry/Place Bound Top")
		(29 "B.CrtYd" user "Package Geometry/Place Bound Bottom")
		(35 "F.Fab" user "Ref Des/Assembly Top")
		(33 "B.Fab" user "Ref Des/Assembly Bottom")
	)
	(footprint ""
		(layer "F.Cu")
		(at 181.566058 -255.560322 180)
		(property "Reference" "J100"
			(at -2.7178 -81.857088 0)
			(unlocked yes)
			(layer "F.SilkS")
			(effects
				(font
					(size 0.7874 0.5842)
					(thickness 0.1524)
				)
			)
		)
		(property "Value" ""
			(at 0 0 180)
			(layer "F.Fab")
			(effects
				(font
					(size 1.27 1.27)
				)
			)
		)
		(duplicate_pad_numbers_are_jumpers no)
		(pad "1" smd rect
			(at -2.050034 -63.324994 90)
			(size 0.519938 1.4986)
			(layers "F.Cu" "F.Mask" "F.Paste")
			(net "P12V_MEM_CPU1")
		)
		(pad "2" smd rect
			(at -2.050034 -62.47511 90)
			(size 0.519938 1.4986)
			(layers "F.Cu" "F.Mask" "F.Paste")
			(net "Net_2368")
		)
		(pad "3" smd rect
			(at -2.050034 -61.624972 90)
			(size 0.519938 1.4986)
			(layers "F.Cu" "F.Mask" "F.Paste")
			(net "P3V3_AUX")
		)
		(pad "4" smd rect
			(at -2.050034 -60.775088 90)
			(size 0.519938 1.4986)
			(layers "F.Cu" "F.Mask" "F.Paste")
			(net "I3C_SPD_DDRI_CPU1_SCL")
		)
		(pad "5" smd rect
			(at -2.050034 -59.92495 90)
			(size 0.519938 1.4986)
			(layers "F.Cu" "F.Mask" "F.Paste")
			(net "I3C_SPD_DDRI_CPU1_SDA")
		)
		(pad "6" smd rect
			(at -2.050034 -59.075066 90)
			(size 0.519938 1.4986)
			(layers "F.Cu" "F.Mask" "F.Paste")
			(net "GND")
		)
		(pad "7" smd rect
			(at -2.050034 -58.224928 90)
			(size 0.519938 1.4986)
			(layers "F.Cu" "F.Mask" "F.Paste")
			(net "M_I_CPU1_SA_DQ<0>")
		)
		(pad "8" smd rect
			(at -2.050034 -57.375044 90)
			(size 0.519938 1.4986)
			(layers "F.Cu" "F.Mask" "F.Paste")
			(net "GND")
		)
		(pad "9" smd rect
			(at -2.050034 -56.524906 90)
			(size 0.519938 1.4986)
			(layers "F.Cu" "F.Mask" "F.Paste")
			(net "M_I_CPU1_SA_DQ<1>")
		)
		(pad "10" smd rect
			(at -2.050034 -55.675022 90)
			(size 0.519938 1.4986)
			(layers "F.Cu" "F.Mask" "F.Paste")
			(net "GND")
		)
		(pad "11" smd rect
			(at -2.050034 -54.824884 90)
			(size 0.519938 1.4986)
			(layers "F.Cu" "F.Mask" "F.Paste")
			(net "M_I_CPU1_SA_DQS_DP<0>")
		)
		(pad "12" smd rect
			(at -2.050034 -53.975 90)
			(size 0.519938 1.4986)
			(layers "F.Cu" "F.Mask" "F.Paste")
			(net "M_I_CPU1_SA_DQS_DN<0>")
		)
		(pad "13" smd rect
			(at -2.050034 -53.125116 90)
			(size 0.519938 1.4986)
			(layers "F.Cu" "F.Mask" "F.Paste")
			(net "GND")
		)
		(pad "14" smd rect
			(at -2.050034 -52.274978 90)
			(size 0.519938 1.4986)
			(layers "F.Cu" "F.Mask" "F.Paste")
			(net "M_I_CPU1_SA_DQ<4>")
		)
		(pad "15" smd rect
			(at -2.050034 -51.425094 90)
			(size 0.519938 1.4986)
			(layers "F.Cu" "F.Mask" "F.Paste")
			(net "GND")
		)
		(pad "16" smd rect
			(at -2.050034 -50.574956 90)
			(size 0.519938 1.4986)
			(layers "F.Cu" "F.Mask" "F.Paste")
			(net "M_I_CPU1_SA_DQ<5>")
		)
		(pad "17" smd rect
			(at -2.050034 -49.725072 90)
			(size 0.519938 1.4986)
			(layers "F.Cu" "F.Mask" "F.Paste")
			(net "GND")
		)
		(pad "18" smd rect
			(at -2.050034 -48.874934 90)
			(size 0.519938 1.4986)
			(layers "F.Cu" "F.Mask" "F.Paste")
			(net "M_I_CPU1_SA_DQ<8>")
		)
		(pad "19" smd rect
			(at -2.050034 -48.02505 90)
			(size 0.519938 1.4986)
			(layers "F.Cu" "F.Mask" "F.Paste")
			(net "GND")
		)
		(pad "20" smd rect
			(at -2.050034 -47.174912 90)
			(size 0.519938 1.4986)
			(layers "F.Cu" "F.Mask" "F.Paste")
			(net "M_I_CPU1_SA_DQ<9>")
		)
		(pad "21" smd rect
			(at -2.050034 -46.325028 90)
			(size 0.519938 1.4986)
			(layers "F.Cu" "F.Mask" "F.Paste")
			(net "GND")
		)
		(pad "22" smd rect
			(at -2.050034 -45.47489 90)
			(size 0.519938 1.4986)
			(layers "F.Cu" "F.Mask" "F.Paste")
			(net "M_I_CPU1_SA_DQS_DP<1>")
		)
		(pad "23" smd rect
			(at -2.050034 -44.625006 90)
			(size 0.519938 1.4986)
			(layers "F.Cu" "F.Mask" "F.Paste")
			(net "M_I_CPU1_SA_DQS_DN<1>")
		)
		(pad "24" smd rect
			(at -2.050034 -43.775122 90)
			(size 0.519938 1.4986)
			(layers "F.Cu" "F.Mask" "F.Paste")
			(net "GND")
		)
		(pad "25" smd rect
			(at -2.050034 -42.924984 90)
			(size 0.519938 1.4986)
			(layers "F.Cu" "F.Mask" "F.Paste")
			(net "M_I_CPU1_SA_DQ<12>")
		)
		(pad "26" smd rect
			(at -2.050034 -42.0751 90)
			(size 0.519938 1.4986)
			(layers "F.Cu" "F.Mask" "F.Paste")
			(net "GND")
		)
		(pad "27" smd rect
			(at -2.050034 -41.224962 90)
			(size 0.519938 1.4986)
			(layers "F.Cu" "F.Mask" "F.Paste")
			(net "M_I_CPU1_SA_DQ<13>")
		)
		(pad "28" smd rect
			(at -2.050034 -40.375078 90)
			(size 0.519938 1.4986)
			(layers "F.Cu" "F.Mask" "F.Paste")
			(net "GND")
		)
		(pad "29" smd rect
			(at -2.050034 -39.52494 90)
			(size 0.519938 1.4986)
			(layers "F.Cu" "F.Mask" "F.Paste")
			(net "M_I_CPU1_SA_DQ<16>")
		)
		(pad "30" smd rect
			(at -2.050034 -38.675056 90)
			(size 0.519938 1.4986)
			(layers "F.Cu" "F.Mask" "F.Paste")
			(net "GND")
		)
		(pad "31" smd rect
			(at -2.050034 -37.824918 90)
			(size 0.519938 1.4986)
			(layers "F.Cu" "F.Mask" "F.Paste")
			(net "M_I_CPU1_SA_DQ<17>")
		)
		(pad "32" smd rect
			(at -2.050034 -36.975034 90)
			(size 0.519938 1.4986)
			(layers "F.Cu" "F.Mask" "F.Paste")
			(net "GND")
		)
		(pad "33" smd rect
			(at -2.050034 -36.124896 90)
			(size 0.519938 1.4986)
			(layers "F.Cu" "F.Mask" "F.Paste")
			(net "M_I_CPU1_SA_DQS_DP<2>")
		)
		(pad "34" smd rect
			(at -2.050034 -35.275012 90)
			(size 0.519938 1.4986)
			(layers "F.Cu" "F.Mask" "F.Paste")
			(net "M_I_CPU1_SA_DQS_DN<2>")
		)
		(pad "35" smd rect
			(at -2.050034 -34.425128 90)
			(size 0.519938 1.4986)
			(layers "F.Cu" "F.Mask" "F.Paste")
			(net "GND")
		)
		(pad "36" smd rect
			(at -2.050034 -33.57499 90)
			(size 0.519938 1.4986)
			(layers "F.Cu" "F.Mask" "F.Paste")
			(net "M_I_CPU1_SA_DQ<20>")
		)
		(pad "37" smd rect
			(at -2.050034 -32.725106 90)
			(size 0.519938 1.4986)
			(layers "F.Cu" "F.Mask" "F.Paste")
			(net "GND")
		)
		(pad "38" smd rect
			(at -2.050034 -31.874968 90)
			(size 0.519938 1.4986)
			(layers "F.Cu" "F.Mask" "F.Paste")
			(net "M_I_CPU1_SA_DQ<21>")
		)
		(pad "39" smd rect
			(at -2.050034 -31.025084 90)
			(size 0.519938 1.4986)
			(layers "F.Cu" "F.Mask" "F.Paste")
			(net "GND")
		)
		(pad "40" smd rect
			(at -2.050034 -30.174946 90)
			(size 0.519938 1.4986)
			(layers "F.Cu" "F.Mask" "F.Paste")
			(net "M_I_CPU1_SA_DQ<24>")
		)
		(pad "41" smd rect
			(at -2.050034 -29.325062 90)
			(size 0.519938 1.4986)
			(layers "F.Cu" "F.Mask" "F.Paste")
			(net "GND")
		)
		(pad "42" smd rect
			(at -2.050034 -28.474924 90)
			(size 0.519938 1.4986)
			(layers "F.Cu" "F.Mask" "F.Paste")
			(net "M_I_CPU1_SA_DQ<25>")
		)
		(pad "43" smd rect
			(at -2.050034 -27.62504 90)
			(size 0.519938 1.4986)
			(layers "F.Cu" "F.Mask" "F.Paste")
			(net "GND")
		)
		(pad "44" smd rect
			(at -2.050034 -26.774902 90)
			(size 0.519938 1.4986)
			(layers "F.Cu" "F.Mask" "F.Paste")
			(net "M_I_CPU1_SA_DQS_DP<3>")
		)
		(pad "45" smd rect
			(at -2.050034 -25.925018 90)
			(size 0.519938 1.4986)
			(layers "F.Cu" "F.Mask" "F.Paste")
			(net "M_I_CPU1_SA_DQS_DN<3>")
		)
		(pad "46" smd rect
			(at -2.050034 -25.07488 90)
			(size 0.519938 1.4986)
			(layers "F.Cu" "F.Mask" "F.Paste")
			(net "GND")
		)
		(pad "47" smd rect
			(at -2.050034 -24.224996 90)
			(size 0.519938 1.4986)
			(layers "F.Cu" "F.Mask" "F.Paste")
			(net "M_I_CPU1_SA_DQ<28>")
		)
		(pad "48" smd rect
			(at -2.050034 -23.375112 90)
			(size 0.519938 1.4986)
			(layers "F.Cu" "F.Mask" "F.Paste")
			(net "GND")
		)
		(pad "49" smd rect
			(at -2.050034 -22.524974 90)
			(size 0.519938 1.4986)
			(layers "F.Cu" "F.Mask" "F.Paste")
			(net "M_I_CPU1_SA_DQ<29>")
		)
		(pad "50" smd rect
			(at -2.050034 -21.67509 90)
			(size 0.519938 1.4986)
			(layers "F.Cu" "F.Mask" "F.Paste")
			(net "GND")
		)
		(pad "51" smd rect
			(at -2.050034 -20.824952 90)
			(size 0.519938 1.4986)
			(layers "F.Cu" "F.Mask" "F.Paste")
			(net "M_I_CPU1_SA_CB<0>")
		)
		(pad "52" smd rect
			(at -2.050034 -19.975068 90)
			(size 0.519938 1.4986)
			(layers "F.Cu" "F.Mask" "F.Paste")
			(net "GND")
		)
		(pad "53" smd rect
			(at -2.050034 -19.12493 90)
			(size 0.519938 1.4986)
			(layers "F.Cu" "F.Mask" "F.Paste")
			(net "M_I_CPU1_SA_CB<1>")
		)
		(pad "54" smd rect
			(at -2.050034 -18.275046 90)
			(size 0.519938 1.4986)
			(layers "F.Cu" "F.Mask" "F.Paste")
			(net "GND")
		)
		(pad "55" smd rect
			(at -2.050034 -17.424908 90)
			(size 0.519938 1.4986)
			(layers "F.Cu" "F.Mask" "F.Paste")
			(net "M_I_CPU1_SA_DQS_DP<4>")
		)
		(pad "56" smd rect
			(at -2.050034 -16.575024 90)
			(size 0.519938 1.4986)
			(layers "F.Cu" "F.Mask" "F.Paste")
			(net "M_I_CPU1_SA_DQS_DN<4>")
		)
		(pad "57" smd rect
			(at -2.050034 -15.724886 90)
			(size 0.519938 1.4986)
			(layers "F.Cu" "F.Mask" "F.Paste")
			(net "GND")
		)
		(pad "58" smd rect
			(at -2.050034 -14.875002 90)
			(size 0.519938 1.4986)
			(layers "F.Cu" "F.Mask" "F.Paste")
			(net "M_I_CPU1_SA_CB<4>")
		)
		(pad "59" smd rect
			(at -2.050034 -14.025118 90)
			(size 0.519938 1.4986)
			(layers "F.Cu" "F.Mask" "F.Paste")
			(net "GND")
		)
		(pad "60" smd rect
			(at -2.050034 -13.17498 90)
			(size 0.519938 1.4986)
			(layers "F.Cu" "F.Mask" "F.Paste")
			(net "M_I_CPU1_SA_CB<5>")
		)
		(pad "61" smd rect
			(at -2.050034 -12.325096 90)
			(size 0.519938 1.4986)
			(layers "F.Cu" "F.Mask" "F.Paste")
			(net "GND")
		)
		(pad "62" smd rect
			(at -2.050034 -11.474958 90)
			(size 0.519938 1.4986)
			(layers "F.Cu" "F.Mask" "F.Paste")
			(net "M_I_CPU1_ALERT_N")
		)
		(pad "63" smd rect
			(at -2.050034 -10.625074 90)
			(size 0.519938 1.4986)
			(layers "F.Cu" "F.Mask" "F.Paste")
			(net "GND")
		)
		(pad "64" smd rect
			(at -2.050034 -9.774936 90)
			(size 0.519938 1.4986)
			(layers "F.Cu" "F.Mask" "F.Paste")
			(net "M_I_CPU1_SA_CS_N<0>")
		)
		(pad "65" smd rect
			(at -2.050034 -8.925052 90)
			(size 0.519938 1.4986)
			(layers "F.Cu" "F.Mask" "F.Paste")
			(net "GND")
		)
		(pad "66" smd rect
			(at -2.050034 -8.074914 90)
			(size 0.519938 1.4986)
			(layers "F.Cu" "F.Mask" "F.Paste")
			(net "M_I_CPU1_SA_CA<0>")
		)
		(pad "67" smd rect
			(at -2.050034 -7.22503 90)
			(size 0.519938 1.4986)
			(layers "F.Cu" "F.Mask" "F.Paste")
			(net "GND")
		)
		(pad "68" smd rect
			(at -2.050034 -6.374892 90)
			(size 0.519938 1.4986)
			(layers "F.Cu" "F.Mask" "F.Paste")
			(net "M_I_CPU1_SA_CA<2>")
		)
		(pad "69" smd rect
			(at -2.050034 -5.525008 90)
			(size 0.519938 1.4986)
			(layers "F.Cu" "F.Mask" "F.Paste")
			(net "GND")
		)
		(pad "70" smd rect
			(at -2.050034 -4.675124 90)
			(size 0.519938 1.4986)
			(layers "F.Cu" "F.Mask" "F.Paste")
			(net "M_I_CPU1_SA_CA<4>")
		)
		(pad "71" smd rect
			(at -2.050034 -3.824986 90)
			(size 0.519938 1.4986)
			(layers "F.Cu" "F.Mask" "F.Paste")
			(net "GND")
		)
		(pad "72" smd rect
			(at -2.050034 -2.975102 90)
			(size 0.519938 1.4986)
			(layers "F.Cu" "F.Mask" "F.Paste")
			(net "M_I_CPU1_SA_CA<6>")
		)
		(pad "73" smd rect
			(at -2.050034 -2.124964 90)
			(size 0.519938 1.4986)
			(layers "F.Cu" "F.Mask" "F.Paste")
			(net "GND")
		)
		(pad "74" smd rect
			(at -2.050034 -1.27508 90)
			(size 0.519938 1.4986)
			(layers "F.Cu" "F.Mask" "F.Paste")
			(net "M_I_CPU1_SA_PAR")
		)
		(pad "75" smd rect
			(at -2.050034 -0.424942 90)
			(size 0.519938 1.4986)
			(layers "F.Cu" "F.Mask" "F.Paste")
			(net "GND")
		)
		(pad "76" smd rect
			(at -2.050034 5.525008 90)
			(size 0.519938 1.4986)
			(layers "F.Cu" "F.Mask" "F.Paste")
			(net "M_I_CPU1_SB_CA<0>")
		)
		(pad "77" smd rect
			(at -2.050034 6.374892 90)
			(size 0.519938 1.4986)
			(layers "F.Cu" "F.Mask" "F.Paste")
			(net "GND")
		)
		(pad "78" smd rect
			(at -2.050034 7.22503 90)
			(size 0.519938 1.4986)
			(layers "F.Cu" "F.Mask" "F.Paste")
			(net "M_I_CPU1_SB_CA<2>")
		)
		(pad "79" smd rect
			(at -2.050034 8.074914 90)
			(size 0.519938 1.4986)
			(layers "F.Cu" "F.Mask" "F.Paste")
			(net "GND")
		)
		(pad "80" smd rect
			(at -2.050034 8.925052 90)
			(size 0.519938 1.4986)
			(layers "F.Cu" "F.Mask" "F.Paste")
			(net "M_I_CPU1_SB_CA<4>")
		)
		(pad "81" smd rect
			(at -2.050034 9.774936 90)
			(size 0.519938 1.4986)
			(layers "F.Cu" "F.Mask" "F.Paste")
			(net "GND")
		)
		(pad "82" smd rect
			(at -2.050034 10.625074 90)
			(size 0.519938 1.4986)
			(layers "F.Cu" "F.Mask" "F.Paste")
			(net "M_I_CPU1_SB_CA<6>")
		)
		(pad "83" smd rect
			(at -2.050034 11.474958 90)
			(size 0.519938 1.4986)
			(layers "F.Cu" "F.Mask" "F.Paste")
			(net "GND")
		)
		(pad "84" smd rect
			(at -2.050034 12.325096 90)
			(size 0.519938 1.4986)
			(layers "F.Cu" "F.Mask" "F.Paste")
			(net "M_I_CPU1_SB_CS_N<0>")
		)
		(pad "85" smd rect
			(at -2.050034 13.17498 90)
			(size 0.519938 1.4986)
			(layers "F.Cu" "F.Mask" "F.Paste")
			(net "GND")
		)
		(pad "86" smd rect
			(at -2.050034 14.025118 90)
			(size 0.519938 1.4986)
			(layers "F.Cu" "F.Mask" "F.Paste")
			(net "M_I_CPU1_SA_RSP<0>")
		)
		(pad "87" smd rect
			(at -2.050034 14.875002 90)
			(size 0.519938 1.4986)
			(layers "F.Cu" "F.Mask" "F.Paste")
			(net "M_I_CPU1_SB_RSP<0>")
		)
		(pad "88" smd rect
			(at -2.050034 15.724886 90)
			(size 0.519938 1.4986)
			(layers "F.Cu" "F.Mask" "F.Paste")
			(net "GND")
		)
		(pad "89" smd rect
			(at -2.050034 16.575024 90)
			(size 0.519938 1.4986)
			(layers "F.Cu" "F.Mask" "F.Paste")
			(net "M_I_CPU1_SB_CB<4>")
		)
		(pad "90" smd rect
			(at -2.050034 17.424908 90)
			(size 0.519938 1.4986)
			(layers "F.Cu" "F.Mask" "F.Paste")
			(net "GND")
		)
		(pad "91" smd rect
			(at -2.050034 18.275046 90)
			(size 0.519938 1.4986)
			(layers "F.Cu" "F.Mask" "F.Paste")
			(net "M_I_CPU1_SB_CB<5>")
		)
		(pad "92" smd rect
			(at -2.050034 19.12493 90)
			(size 0.519938 1.4986)
			(layers "F.Cu" "F.Mask" "F.Paste")
			(net "GND")
		)
		(pad "93" smd rect
			(at -2.050034 19.975068 90)
			(size 0.519938 1.4986)
			(layers "F.Cu" "F.Mask" "F.Paste")
			(net "M_I_CPU1_SB_DQS_DP<9>")
		)
		(pad "94" smd rect
			(at -2.050034 20.824952 90)
			(size 0.519938 1.4986)
			(layers "F.Cu" "F.Mask" "F.Paste")
			(net "M_I_CPU1_SB_DQS_DN<9>")
		)
		(pad "95" smd rect
			(at -2.050034 21.67509 90)
			(size 0.519938 1.4986)
			(layers "F.Cu" "F.Mask" "F.Paste")
			(net "GND")
		)
		(pad "96" smd rect
			(at -2.050034 22.524974 90)
			(size 0.519938 1.4986)
			(layers "F.Cu" "F.Mask" "F.Paste")
			(net "M_I_CPU1_SB_CB<0>")
		)
		(pad "97" smd rect
			(at -2.050034 23.375112 90)
			(size 0.519938 1.4986)
			(layers "F.Cu" "F.Mask" "F.Paste")
			(net "GND")
		)
		(pad "98" smd rect
			(at -2.050034 24.224996 90)
			(size 0.519938 1.4986)
			(layers "F.Cu" "F.Mask" "F.Paste")
			(net "M_I_CPU1_SB_CB<1>")
		)
		(pad "99" smd rect
			(at -2.050034 25.07488 90)
			(size 0.519938 1.4986)
			(layers "F.Cu" "F.Mask" "F.Paste")
			(net "GND")
		)
		(pad "100" smd rect
			(at -2.050034 25.925018 90)
			(size 0.519938 1.4986)
			(layers "F.Cu" "F.Mask" "F.Paste")
			(net "M_I_CPU1_SB_DQ<0>")
		)
		(pad "101" smd rect
			(at -2.050034 26.774902 90)
			(size 0.519938 1.4986)
			(layers "F.Cu" "F.Mask" "F.Paste")
			(net "GND")
		)
		(pad "102" smd rect
			(at -2.050034 27.62504 90)
			(size 0.519938 1.4986)
			(layers "F.Cu" "F.Mask" "F.Paste")
			(net "M_I_CPU1_SB_DQ<1>")
		)
		(pad "103" smd rect
			(at -2.050034 28.474924 90)
			(size 0.519938 1.4986)
			(layers "F.Cu" "F.Mask" "F.Paste")
			(net "GND")
		)
		(pad "104" smd rect
			(at -2.050034 29.325062 90)
			(size 0.519938 1.4986)
			(layers "F.Cu" "F.Mask" "F.Paste")
			(net "M_I_CPU1_SB_DQS_DP<0>")
		)
		(pad "105" smd rect
			(at -2.050034 30.174946 90)
			(size 0.519938 1.4986)
			(layers "F.Cu" "F.Mask" "F.Paste")
			(net "M_I_CPU1_SB_DQS_DN<0>")
		)
		(pad "106" smd rect
			(at -2.050034 31.025084 90)
			(size 0.519938 1.4986)
			(layers "F.Cu" "F.Mask" "F.Paste")
			(net "GND")
		)
		(pad "107" smd rect
			(at -2.050034 31.874968 90)
			(size 0.519938 1.4986)
			(layers "F.Cu" "F.Mask" "F.Paste")
			(net "M_I_CPU1_SB_DQ<4>")
		)
		(pad "108" smd rect
			(at -2.050034 32.725106 90)
			(size 0.519938 1.4986)
			(layers "F.Cu" "F.Mask" "F.Paste")
			(net "GND")
		)
		(pad "109" smd rect
			(at -2.050034 33.57499 90)
			(size 0.519938 1.4986)
			(layers "F.Cu" "F.Mask" "F.Paste")
			(net "M_I_CPU1_SB_DQ<5>")
		)
		(pad "110" smd rect
			(at -2.050034 34.425128 90)
			(size 0.519938 1.4986)
			(layers "F.Cu" "F.Mask" "F.Paste")
			(net "GND")
		)
		(pad "111" smd rect
			(at -2.050034 35.275012 90)
			(size 0.519938 1.4986)
			(layers "F.Cu" "F.Mask" "F.Paste")
			(net "M_I_CPU1_SB_DQ<8>")
		)
		(pad "112" smd rect
			(at -2.050034 36.124896 90)
			(size 0.519938 1.4986)
			(layers "F.Cu" "F.Mask" "F.Paste")
			(net "GND")
		)
		(pad "113" smd rect
			(at -2.050034 36.975034 90)
			(size 0.519938 1.4986)
			(layers "F.Cu" "F.Mask" "F.Paste")
			(net "M_I_CPU1_SB_DQ<9>")
		)
	)
)
